# T6G (Grand Teton) — schematic netlist excerpt (pin names and nets, part order shuffled) for the footprints in the layout excerpt that follows; sources: Cadence DE-HDL packaged netlist, KiCad conversion of 04192023_DAF0TMB3IC0_F0TG_MB_C_brd_V02_OCP.brd

R3654  Q_RES  33.2 1% CHIP  pkg 0402LF  page 234 : A = RST_USB_HUB_N ; B = RST_USB_HUB_R_N
R2788  Q_RES  0 5% EMPTY  pkg 0402LF  page 234 : A = USB2_HOST_BMC_B_BUF_DP ; B = USB2_HUB_BUF_SWB_R_DP

(kicad_pcb
	(version 20260206)
	(generator "pcbnew")
	(generator_version "10.0")
	(general
		(thickness 1.6)
		(legacy_teardrops no)
	)
	(paper "A4")
	(title_block
		(title "04192023_DAF0TMB3IC0_F0TG_MB_C_brd_V02_OCP.brd")
		(comment 1 "Grand Teton / footprints 814-816 of 8354")
	)
	(layers
		(0 "F.Cu" signal "TOP")
		(4 "In1.Cu" signal "GND")
		(6 "In2.Cu" signal "IN1")
		(8 "In3.Cu" signal "GND1")
		(10 "In4.Cu" signal "IN2")
		(12 "In5.Cu" signal "GND2")
		(14 "In6.Cu" signal "IN3")
		(16 "In7.Cu" signal "GND3")
		(18 "In8.Cu" signal "VCC")
		(20 "In9.Cu" signal "VCC1")
		(22 "In10.Cu" signal "GND4")
		(24 "In11.Cu" signal "IN4")
		(26 "In12.Cu" signal "GND5")
		(28 "In13.Cu" signal "IN5")
		(30 "In14.Cu" signal "GND6")
		(32 "In15.Cu" signal "IN6")
		(34 "In16.Cu" signal "GND7")
		(2 "B.Cu" signal "BOTTOM")
		(9 "F.Adhes" user "F.Adhesive")
		(11 "B.Adhes" user "B.Adhesive")
		(13 "F.Paste" user "Package Geometry/Pastemask Top")
		(15 "B.Paste" user "Package Geometry/Pastemask Bottom")
		(5 "F.SilkS" user "Ref Des/Silkscreen Top")
		(7 "B.SilkS" user "Ref Des/Silkscreen Bottom")
		(1 "F.Mask" user "Board Geometry/Soldermask Top")
		(3 "B.Mask" user "Board Geometry/Soldermask Bottom")
		(17 "Dwgs.User" user "User.Drawings")
		(19 "Cmts.User" user "User.Comments")
		(21 "Eco1.User" user "User.Eco1")
		(23 "Eco2.User" user "User.Eco2")
		(25 "Edge.Cuts" user "Board Geometry/Outline")
		(27 "Margin" user)
		(31 "F.CrtYd" user "Package Geometry/Place Bound Top")
		(29 "B.CrtYd" user "Package Geometry/Place Bound Bottom")
		(35 "F.Fab" user "Ref Des/Assembly Top")
		(33 "B.Fab" user "Ref Des/Assembly Bottom")
	)
	(footprint ""
		(layer "F.Cu")
		(at 11.421618 -106.28249 -90)
		(property "Reference" "R2788"
			(at 0 0 270)
			(layer "F.SilkS")
			(hide yes)
			(effects
				(font
					(size 1.27 1.27)
				)
			)
		)
		(property "Value" ""
			(at 0 0 270)
			(layer "F.Fab")
			(effects
				(font
					(size 1.27 1.27)
				)
			)
		)
		(duplicate_pad_numbers_are_jumpers no)
		(fp_line
			(start -0.7874 0.4064)
			(end -0.7874 -0.4064)
			(stroke
				(width 0.1524)
				(type default)
			)
			(layer "F.SilkS")
		)
		(fp_line
			(start 0.7874 0.4064)
			(end -0.7874 0.4064)
			(stroke
				(width 0.1524)
				(type default)
			)
			(layer "F.SilkS")
		)
		(fp_line
			(start -0.7874 -0.4064)
			(end 0.7874 -0.4064)
			(stroke
				(width 0.1524)
				(type default)
			)
			(layer "F.SilkS")
		)
		(fp_line
			(start 0.7874 -0.4064)
			(end 0.7874 0.4064)
			(stroke
				(width 0.1524)
				(type default)
			)
			(layer "F.SilkS")
		)
		(fp_line
			(start -0.67945 0.3048)
			(end -0.67945 -0.305054)
			(stroke
				(width 0.1)
				(type default)
			)
			(layer "F.Fab")
		)
		(fp_line
			(start -0.12065 0.3048)
			(end -0.67945 0.3048)
			(stroke
				(width 0.1)
				(type default)
			)
			(layer "F.Fab")
		)
		(fp_line
			(start 0.120396 0.3048)
			(end 0.120396 0.2794)
			(stroke
				(width 0.1)
				(type default)
			)
			(layer "F.Fab")
		)
		(fp_line
			(start 0.67945 0.3048)
			(end 0.120396 0.3048)
			(stroke
				(width 0.1)
				(type default)
			)
			(layer "F.Fab")
		)
		(fp_line
			(start -0.12065 0.2794)
			(end -0.12065 0.3048)
			(stroke
				(width 0.1)
				(type default)
			)
			(layer "F.Fab")
		)
		(fp_line
			(start 0.120396 0.2794)
			(end -0.12065 0.2794)
			(stroke
				(width 0.1)
				(type default)
			)
			(layer "F.Fab")
		)
		(fp_line
			(start -0.12065 -0.2794)
			(end 0.12065 -0.2794)
			(stroke
				(width 0.1)
				(type default)
			)
			(layer "F.Fab")
		)
		(fp_line
			(start 0.12065 -0.2794)
			(end 0.12065 -0.3048)
			(stroke
				(width 0.1)
				(type default)
			)
			(layer "F.Fab")
		)
		(fp_line
			(start 0.12065 -0.3048)
			(end 0.67945 -0.3048)
			(stroke
				(width 0.1)
				(type default)
			)
			(layer "F.Fab")
		)
		(fp_line
			(start 0.67945 -0.3048)
			(end 0.67945 0.3048)
			(stroke
				(width 0.1)
				(type default)
			)
			(layer "F.Fab")
		)
		(fp_line
			(start -0.67945 -0.305054)
			(end -0.12065 -0.305054)
			(stroke
				(width 0.1)
				(type default)
			)
			(layer "F.Fab")
		)
		(fp_line
			(start -0.12065 -0.305054)
			(end -0.12065 -0.2794)
			(stroke
				(width 0.1)
				(type default)
			)
			(layer "F.Fab")
		)
		(pad "1" smd rect
			(at -0.40005 0 90)
			(size 0.4572 0.508)
			(layers "F.Cu" "F.Mask" "F.Paste")
			(net "USB2_HOST_BMC_B_BUF_DP")
		)
		(pad "2" smd rect
			(at 0.40005 0 90)
			(size 0.4572 0.508)
			(layers "F.Cu" "F.Mask" "F.Paste")
			(net "USB2_HUB_BUF_SWB_R_DP")
		)
	)
	(footprint ""
		(layer "F.Cu")
		(at 1.551686 -424.956732)
		(property "Reference" "BIOS_LABEL"
			(at -2.487168 2.245106 90)
			(unlocked yes)
			(layer "F.SilkS")
			(effects
				(font
					(size 0.7874 0.5842)
					(thickness 0.1524)
				)
				(justify left)
			)
		)
		(property "Value" ""
			(at 0 0 0)
			(layer "F.Fab")
			(effects
				(font
					(size 1.27 1.27)
				)
			)
		)
		(duplicate_pad_numbers_are_jumpers no)
		(pad "1" smd circle
			(at 0 0)
			(size 0.762 0.762)
			(layers "F.Cu" "F.Mask" "F.Paste")
			(net "Net_2230")
		)
	)
	(footprint ""
		(layer "F.Cu")
		(at 9.908032 -92.687648 90)
		(property "Reference" "R3654"
			(at 0 0 90)
			(layer "F.SilkS")
			(hide yes)
			(effects
				(font
					(size 1.27 1.27)
				)
			)
		)
		(property "Value" ""
			(at 0 0 90)
			(layer "F.Fab")
			(effects
				(font
					(size 1.27 1.27)
				)
			)
		)
		(duplicate_pad_numbers_are_jumpers no)
		(fp_line
			(start 0.7874 -0.4064)
			(end 0.7874 0.4064)
			(stroke
				(width 0.1524)
				(type default)
			)
			(layer "F.SilkS")
		)
		(fp_line
			(start -0.7874 -0.4064)
			(end 0.7874 -0.4064)
			(stroke
				(width 0.1524)
				(type default)
			)
			(layer "F.SilkS")
		)
		(fp_line
			(start 0.7874 0.4064)
			(end -0.7874 0.4064)
			(stroke
				(width 0.1524)
				(type default)
			)
			(layer "F.SilkS")
		)
		(fp_line
			(start -0.7874 0.4064)
			(end -0.7874 -0.4064)
			(stroke
				(width 0.1524)
				(type default)
			)
			(layer "F.SilkS")
		)
		(fp_line
			(start -0.12065 -0.305054)
			(end -0.12065 -0.2794)
			(stroke
				(width 0.1)
				(type default)
			)
			(layer "F.Fab")
		)
		(fp_line
			(start -0.67945 -0.305054)
			(end -0.12065 -0.305054)
			(stroke
				(width 0.1)
				(type default)
			)
			(layer "F.Fab")
		)
		(fp_line
			(start 0.67945 -0.3048)
			(end 0.67945 0.3048)
			(stroke
				(width 0.1)
				(type default)
			)
			(layer "F.Fab")
		)
		(fp_line
			(start 0.12065 -0.3048)
			(end 0.67945 -0.3048)
			(stroke
				(width 0.1)
				(type default)
			)
			(layer "F.Fab")
		)
		(fp_line
			(start 0.12065 -0.2794)
			(end 0.12065 -0.3048)
			(stroke
				(width 0.1)
				(type default)
			)
			(layer "F.Fab")
		)
		(fp_line
			(start -0.12065 -0.2794)
			(end 0.12065 -0.2794)
			(stroke
				(width 0.1)
				(type default)
			)
			(layer "F.Fab")
		)
		(fp_line
			(start 0.120396 0.2794)
			(end -0.12065 0.2794)
			(stroke
				(width 0.1)
				(type default)
			)
			(layer "F.Fab")
		)
		(fp_line
			(start -0.12065 0.2794)
			(end -0.12065 0.3048)
			(stroke
				(width 0.1)
				(type default)
			)
			(layer "F.Fab")
		)
		(fp_line
			(start 0.67945 0.3048)
			(end 0.120396 0.3048)
			(stroke
				(width 0.1)
				(type default)
			)
			(layer "F.Fab")
		)
		(fp_line
			(start 0.120396 0.3048)
			(end 0.120396 0.2794)
			(stroke
				(width 0.1)
				(type default)
			)
			(layer "F.Fab")
		)
		(fp_line
			(start -0.12065 0.3048)
			(end -0.67945 0.3048)
			(stroke
				(width 0.1)
				(type default)
			)
			(layer "F.Fab")
		)
		(fp_line
			(start -0.67945 0.3048)
			(end -0.67945 -0.305054)
			(stroke
				(width 0.1)
				(type default)
			)
			(layer "F.Fab")
		)
		(pad "1" smd circle
			(at -0.40005 0 90)
			(size 0 0)
			(layers "F.Cu" "F.Mask" "F.Paste")
			(net "RST_USB_HUB_N")
		)
		(pad "2" smd circle
			(at 0.40005 0 90)
			(size 0 0)
			(layers "F.Cu" "F.Mask" "F.Paste")
			(net "RST_USB_HUB_R_N")
		)
	)
)
